#ISCELL
  logical_power cad_note *
  *
#ISCELL
  mstr_misc dns *
  *
#ISCELL
  pure_quanta quanta_title_block_c *
  *
#ISCELL
  standard offpage *
  page237_i33
#ISCELL
  logical_power universal_gnd *
  page237_i34
#CELL
  pure_quanta q_cap *
  page237_i35
#CELL
  pure_quanta q_res *
  page237_i43
#CELL
  pure_quanta q_res *
  page237_i44
#ISCELL
  logical_power universal_gnd *
  page237_i45
#CELL
  pure_quanta q_res *
  page237_i46
#ISCELL
  logical_power universal_gnd *
  page237_i47
#CELL
  pure_quanta q_cap *
  page237_i48
#ISCELL
  logical_power universal_gnd *
  page237_i49
#CELL
  pure_quanta q_cap *
  page237_i50
#CELL
  pure_quanta mp5016gqhlz *
  page237_i51
#ISCELL
  logical_power universal_power *
  page237_i52
#ISCELL
  logical_power universal_gnd *
  page237_i53
#CELL
  pure_quanta q_cap *
  page237_i54
#ISCELL
  logical_power universal_gnd *
  page237_i55
#CELL
  pure_quanta q_cap *
  page237_i56
#ISCELL
  logical_power universal_power *
  page237_i57
#ISCELL
  standard offpage *
  page237_i58
#ISCELL
  logical_power gnd *
  page237_i59
#ISCELL
  logical_power gnd *
  page237_i60
#CELL
  pure_quanta q_res *
  page237_i61
#CELL
  pure_quanta q_cap *
  page237_i62
#ISCELL
  logical_power gnd *
  page237_i63
#ISCELL
  logical_power gnd *
  page237_i64
#CELL
  pure_quanta q_cap *
  page237_i65
#CELL
  pure_quanta q_res *
  page237_i66
#ISCELL
  logical_power gnd *
  page237_i67
#CELL
  pure_quanta q_cap *
  page237_i68
#ISCELL
  logical_power gnd *
  page237_i69
#CELL
  pure_quanta rs31312r *
  page237_i70
#ISCELL
  logical_power gnd *
  page237_i71
#CELL
  pure_quanta q_res *
  page237_i72
#CELL
  pure_quanta q_cap *
  page237_i73
#CELL
  pure_quanta q_res *
  page237_i74
#CELL
  pure_quanta q_res *
  page237_i75
#ISCELL
  logical_power vccaux15 *
  page237_i76
#CELL
  pure_quanta q_res *
  page237_i77
#ISCELL
  standard offpage *
  page237_i78
#ISCELL
  logical_power vccaux15 *
  page237_i79
#CELL
  pure_quanta q_res *
  page237_i80
#CELL
  pure_quanta q_res *
  page237_i81
#ISCELL
  logical_power gnd *
  page237_i82
#CELL
  pure_quanta q_res *
  page237_i83
#CELL
  pure_quanta q_res *
  page237_i84
#CELL
  pure_quanta q_res *
  page237_i85
#ISCELL
  logical_power universal_power *
  page237_i86
#CELL
  pure_quanta q_res *
  page237_i87
#ISCELL
  standard offpage *
  page237_i88
#ISCELL
  logical_power universal_power *
  page237_i89
#ISCELL
  logical_power gnd *
  page237_i90
#CELL
  pure_quanta q_cap *
  page237_i91
#ISCELL
  logical_power universal_power *
  page237_i92
#ISCELL
  standard offpage *
  page237_i93
#ISCELL
  standard offpage *
  page237_i94
#CELL
  pure_quanta q_cap *
  page237_i95
#ISCELL
  standard offpage *
  page237_i96
